(kicad_pcb
	(version 20260206)
	(generator "pcbnew")
	(generator_version "10.0")
	(general
		(thickness 1.6)
		(legacy_teardrops no)
	)
	(paper "A4")
	(title_block
		(title "timecard-production-celestica-r4006 — R4006-B0001-02_R01.brd")
		(comment 1 "Time Appliance Project (Time Card) / footprints 43-46 of 1113")
	)
	(layers
		(0 "F.Cu" signal "TOP")
		(4 "In1.Cu" signal "L02_GND1")
		(6 "In2.Cu" signal "L03_SIG1")
		(8 "In3.Cu" signal "L04_GND2")
		(10 "In4.Cu" signal "L05_VCC1")
		(12 "In5.Cu" signal "L06_VCC2")
		(14 "In6.Cu" signal "L07_GND3")
		(16 "In7.Cu" signal "L08_SIG2")
		(18 "In8.Cu" signal "L09_GND4")
		(2 "B.Cu" signal "BOTTOM")
		(9 "F.Adhes" user "F.Adhesive")
		(11 "B.Adhes" user "B.Adhesive")
		(13 "F.Paste" user "Package Geometry/Pastemask Top")
		(15 "B.Paste" user "Package Geometry/Pastemask Bottom")
		(5 "F.SilkS" user "Ref Des/Silkscreen Top")
		(7 "B.SilkS" user "Ref Des/Silkscreen Bottom")
		(1 "F.Mask" user "Board Geometry/Soldermask Top")
		(3 "B.Mask" user "Board Geometry/Soldermask Bottom")
		(17 "Dwgs.User" user "User.Drawings")
		(19 "Cmts.User" user "User.Comments")
		(21 "Eco1.User" user "User.Eco1")
		(23 "Eco2.User" user "User.Eco2")
		(25 "Edge.Cuts" user "Board Geometry/Outline")
		(27 "Margin" user)
		(31 "F.CrtYd" user "Package Geometry/Place Bound Top")
		(29 "B.CrtYd" user "Package Geometry/Place Bound Bottom")
		(35 "F.Fab" user "Ref Des/Assembly Top")
		(33 "B.Fab" user "Ref Des/Assembly Bottom")
	)
	(footprint ""
		(layer "F.Cu")
		(at 5.9944 -39.318692 90)
		(property "Reference" "R124"
			(at 2.337308 0.08255 90)
			(unlocked yes)
			(layer "F.SilkS")
			(effects
				(font
					(size 0.635 0.4064)
					(thickness 0.1524)
				)
			)
		)
		(property "Value" "VAL*"
			(at 0.02032 2.13233 90)
			(unlocked yes)
			(layer "F.Fab")
			(hide yes)
			(effects
				(font
					(size 0.7874 0.5842)
					(thickness 0.1524)
				)
			)
		)
		(property "Device Type" "RESISTOR-G155-11000-01,100OHM,A"
			(at 0.008382 1.210564 90)
			(unlocked yes)
			(layer "F.Fab")
			(hide yes)
			(effects
				(font
					(size 0.7874 0.5842)
					(thickness 0.1524)
				)
			)
		)
		(property "User Part Number" "PARTNUM*"
			(at 0.02032 4.024884 90)
			(unlocked yes)
			(layer "Cmts.User")
			(hide yes)
			(effects
				(font
					(size 0.7874 0.5842)
					(thickness 0.1524)
				)
			)
		)
		(property "Tolerance" "TOL*"
			(at 0.044704 3.05435 90)
			(unlocked yes)
			(layer "Cmts.User")
			(hide yes)
			(effects
				(font
					(size 0.7874 0.5842)
					(thickness 0.1524)
				)
			)
		)
		(duplicate_pad_numbers_are_jumpers no)
		(fp_line
			(start 1.143 -0.5588)
			(end -1.143 -0.5588)
			(stroke
				(width 0.1)
				(type default)
			)
			(layer "F.SilkS")
		)
		(fp_line
			(start -1.143 -0.5588)
			(end -1.143 0.5588)
			(stroke
				(width 0.1)
				(type default)
			)
			(layer "F.SilkS")
		)
		(fp_line
			(start 1.143 0.5588)
			(end 1.143 -0.5588)
			(stroke
				(width 0.1)
				(type default)
			)
			(layer "F.SilkS")
		)
		(fp_line
			(start -1.143 0.5588)
			(end 1.143 0.5588)
			(stroke
				(width 0.1)
				(type default)
			)
			(layer "F.SilkS")
		)
		(fp_poly
			(pts
				(xy -1.143 0.5588) (xy 1.143 0.5588) (xy 1.143 -0.5588) (xy -1.143 -0.5588)
			)
			(stroke
				(width 0)
				(type default)
			)
			(fill no)
			(layer "F.CrtYd")
		)
		(fp_line
			(start 0.508 -0.3048)
			(end -0.508 -0.3048)
			(stroke
				(width 0.1)
				(type default)
			)
			(layer "F.Fab")
		)
		(fp_line
			(start -0.508 -0.3048)
			(end -0.508 0.3048)
			(stroke
				(width 0.1)
				(type default)
			)
			(layer "F.Fab")
		)
		(fp_line
			(start 0.508 0.3048)
			(end 0.508 -0.3048)
			(stroke
				(width 0.1)
				(type default)
			)
			(layer "F.Fab")
		)
		(fp_line
			(start -0.508 0.3048)
			(end 0.508 0.3048)
			(stroke
				(width 0.1)
				(type default)
			)
			(layer "F.Fab")
		)
		(pad "1" smd rect
			(at -0.5334 0 90)
			(size 0.7112 0.6096)
			(layers "F.Cu" "F.Mask" "F.Paste")
			(net "FPGA_OUT_SMA1_LED_BLUE_N")
		)
		(pad "2" smd rect
			(at 0.5334 0 90)
			(size 0.7112 0.6096)
			(layers "F.Cu" "F.Mask" "F.Paste")
			(net "UNNAMED_14_LED4PV14_I265_1")
		)
		(zone
			(layer "F.Cu")
			(hatch none 0.5)
			(connect_pads
				(clearance 0)
			)
			(min_thickness 0.25)
			(keepout
				(tracks not_allowed)
				(vias allowed)
				(pads allowed)
				(copperpour not_allowed)
				(footprints allowed)
			)
			(placement
				(enabled no)
				(sheetname "")
			)
			(fill
				(thermal_gap 0.5)
				(thermal_bridge_width 0.5)
				(island_removal_mode 0)
			)
			(polygon
				(pts
					(xy 6.2992 -39.242492) (xy 6.2992 -39.394892) (xy 5.6896 -39.394892) (xy 5.6896 -39.242492)
				)
			)
		)
		(zone
			(layer "F.Cu")
			(hatch none 0.5)
			(connect_pads
				(clearance 0)
			)
			(min_thickness 0.25)
			(keepout
				(tracks allowed)
				(vias not_allowed)
				(pads allowed)
				(copperpour not_allowed)
				(footprints allowed)
			)
			(placement
				(enabled no)
				(sheetname "")
			)
			(fill
				(thermal_gap 0.5)
				(thermal_bridge_width 0.5)
				(island_removal_mode 0)
			)
			(polygon
				(pts
					(xy 6.2992 -39.242492) (xy 6.2992 -39.394892) (xy 5.6896 -39.394892) (xy 5.6896 -39.242492)
				)
			)
		)
	)
	(footprint ""
		(layer "F.Cu")
		(at 18.288 -87.63 90)
		(property "Reference" "U17"
			(at -1.524 -2.50063 90)
			(unlocked yes)
			(layer "F.SilkS")
			(effects
				(font
					(size 0.7874 0.5842)
					(thickness 0.1524)
				)
			)
		)
		(property "Value" ""
			(at 0 0 90)
			(layer "F.Fab")
			(effects
				(font
					(size 1.27 1.27)
				)
			)
		)
		(property "User Part Number" "PARTNUM*"
			(at 0.1016 3.45567 90)
			(unlocked yes)
			(layer "Cmts.User")
			(hide yes)
			(effects
				(font
					(size 0.7874 0.5842)
					(thickness 0.1524)
				)
			)
		)
		(property "Device Type" "CL1001485A-G122-00019-01"
			(at 0.1016 2.54127 90)
			(unlocked yes)
			(layer "F.Fab")
			(hide yes)
			(effects
				(font
					(size 0.7874 0.5842)
					(thickness 0.1524)
				)
			)
		)
		(duplicate_pad_numbers_are_jumpers no)
		(fp_line
			(start 1.0541 -1.704086)
			(end -1.0541 -1.704086)
			(stroke
				(width 0.1)
				(type default)
			)
			(layer "F.SilkS")
		)
		(fp_line
			(start -1.0541 -1.704086)
			(end -1.0541 -1.45796)
			(stroke
				(width 0.1)
				(type default)
			)
			(layer "F.SilkS")
		)
		(fp_line
			(start 2.286 -1.45796)
			(end 1.0541 -1.45796)
			(stroke
				(width 0.1)
				(type default)
			)
			(layer "F.SilkS")
		)
		(fp_line
			(start 1.0541 -1.45796)
			(end 1.0541 -1.704086)
			(stroke
				(width 0.1)
				(type default)
			)
			(layer "F.SilkS")
		)
		(fp_line
			(start -1.0541 -1.45796)
			(end -2.286 -1.45796)
			(stroke
				(width 0.1)
				(type default)
			)
			(layer "F.SilkS")
		)
		(fp_line
			(start -2.286 -1.45796)
			(end -2.286 1.45796)
			(stroke
				(width 0.1)
				(type default)
			)
			(layer "F.SilkS")
		)
		(fp_line
			(start 2.286 1.45796)
			(end 2.286 -1.45796)
			(stroke
				(width 0.1)
				(type default)
			)
			(layer "F.SilkS")
		)
		(fp_line
			(start 1.0541 1.45796)
			(end 2.286 1.45796)
			(stroke
				(width 0.1)
				(type default)
			)
			(layer "F.SilkS")
		)
		(fp_line
			(start -1.0541 1.45796)
			(end -1.0541 1.704086)
			(stroke
				(width 0.1)
				(type default)
			)
			(layer "F.SilkS")
		)
		(fp_line
			(start -2.286 1.45796)
			(end -1.0541 1.45796)
			(stroke
				(width 0.1)
				(type default)
			)
			(layer "F.SilkS")
		)
		(fp_line
			(start 1.0541 1.704086)
			(end 1.0541 1.45796)
			(stroke
				(width 0.1)
				(type default)
			)
			(layer "F.SilkS")
		)
		(fp_line
			(start -1.0541 1.704086)
			(end 1.0541 1.704086)
			(stroke
				(width 0.1)
				(type default)
			)
			(layer "F.SilkS")
		)
		(fp_poly
			(pts
				(arc
					(start -2.8956 -0.6858)
					(mid -2.8956 -1.4478)
					(end -2.8956 -0.6858)
				)
			)
			(stroke
				(width 0)
				(type default)
			)
			(fill yes)
			(layer "F.SilkS")
		)
		(fp_rect
			(start 2.54 1.9558)
			(end -2.54 -1.9558)
			(stroke
				(width 0)
				(type default)
			)
			(fill no)
			(layer "F.CrtYd")
		)
		(fp_line
			(start 0.8001 -1.450086)
			(end 0.8001 -1.199896)
			(stroke
				(width 0.1)
				(type default)
			)
			(layer "F.Fab")
		)
		(fp_line
			(start -0.8001 -1.450086)
			(end 0.8001 -1.450086)
			(stroke
				(width 0.1)
				(type default)
			)
			(layer "F.Fab")
		)
		(fp_line
			(start 0.599948 -1.249934)
			(end 0.8001 -1.450086)
			(stroke
				(width 0.1)
				(type default)
			)
			(layer "F.Fab")
		)
		(fp_line
			(start 0.599948 -1.249934)
			(end 0.599948 1.249934)
			(stroke
				(width 0.1)
				(type default)
			)
			(layer "F.Fab")
		)
		(fp_line
			(start -0.599948 -1.249934)
			(end -0.8001 -1.450086)
			(stroke
				(width 0.1)
				(type default)
			)
			(layer "F.Fab")
		)
		(fp_line
			(start -0.599948 -1.249934)
			(end 0.599948 -1.249934)
			(stroke
				(width 0.1)
				(type default)
			)
			(layer "F.Fab")
		)
		(fp_line
			(start 1.500124 -1.199896)
			(end 1.500124 -0.700024)
			(stroke
				(width 0.1)
				(type default)
			)
			(layer "F.Fab")
		)
		(fp_line
			(start 0.700024 -1.199896)
			(end 1.500124 -1.199896)
			(stroke
				(width 0.1)
				(type default)
			)
			(layer "F.Fab")
		)
		(fp_line
			(start -0.700024 -1.199896)
			(end -0.700024 -0.700024)
			(stroke
				(width 0.1)
				(type default)
			)
			(layer "F.Fab")
		)
		(fp_line
			(start -0.8001 -1.199896)
			(end -0.8001 -1.450086)
			(stroke
				(width 0.1)
				(type default)
			)
			(layer "F.Fab")
		)
		(fp_line
			(start -1.500124 -1.199896)
			(end -0.700024 -1.199896)
			(stroke
				(width 0.1)
				(type default)
			)
			(layer "F.Fab")
		)
		(fp_line
			(start 1.500124 -0.700024)
			(end 0.700024 -0.700024)
			(stroke
				(width 0.1)
				(type default)
			)
			(layer "F.Fab")
		)
		(fp_line
			(start 0.8001 -0.700024)
			(end 0.8001 -0.249936)
			(stroke
				(width 0.1)
				(type default)
			)
			(layer "F.Fab")
		)
		(fp_line
			(start 0.700024 -0.700024)
			(end 0.700024 -1.199896)
			(stroke
				(width 0.1)
				(type default)
			)
			(layer "F.Fab")
		)
		(fp_line
			(start -0.700024 -0.700024)
			(end -1.500124 -0.700024)
			(stroke
				(width 0.1)
				(type default)
			)
			(layer "F.Fab")
		)
		(fp_line
			(start -0.8001 -0.700024)
			(end -0.8001 -0.249936)
			(stroke
				(width 0.1)
				(type default)
			)
			(layer "F.Fab")
		)
		(fp_line
			(start -1.500124 -0.700024)
			(end -1.500124 -1.199896)
			(stroke
				(width 0.1)
				(type default)
			)
			(layer "F.Fab")
		)
		(fp_line
			(start 1.500124 -0.249936)
			(end 1.500124 0.249936)
			(stroke
				(width 0.1)
				(type default)
			)
			(layer "F.Fab")
		)
		(fp_line
			(start 0.8001 -0.249936)
			(end 0.700024 -0.249936)
			(stroke
				(width 0.1)
				(type default)
			)
			(layer "F.Fab")
		)
		(fp_line
			(start 0.700024 -0.249936)
			(end 1.500124 -0.249936)
			(stroke
				(width 0.1)
				(type default)
			)
			(layer "F.Fab")
		)
		(fp_line
			(start 0.700024 -0.249936)
			(end 0.700024 0.249936)
			(stroke
				(width 0.1)
				(type default)
			)
			(layer "F.Fab")
		)
		(fp_line
			(start -0.700024 -0.249936)
			(end -0.700024 0.249936)
			(stroke
				(width 0.1)
				(type default)
			)
			(layer "F.Fab")
		)
		(fp_line
			(start -1.500124 -0.249936)
			(end -0.700024 -0.249936)
			(stroke
				(width 0.1)
				(type default)
			)
			(layer "F.Fab")
		)
		(fp_line
			(start 1.500124 0.249936)
			(end 0.700024 0.249936)
			(stroke
				(width 0.1)
				(type default)
			)
			(layer "F.Fab")
		)
		(fp_line
			(start 0.8001 0.249936)
			(end 0.8001 0.700024)
			(stroke
				(width 0.1)
				(type default)
			)
			(layer "F.Fab")
		)
		(fp_line
			(start 0.700024 0.249936)
			(end 0.700024 -0.249936)
			(stroke
				(width 0.1)
				(type default)
			)
			(layer "F.Fab")
		)
		(fp_line
			(start 0.700024 0.249936)
			(end 0.8001 0.249936)
			(stroke
				(width 0.1)
				(type default)
			)
			(layer "F.Fab")
		)
		(fp_line
			(start -0.700024 0.249936)
			(end -1.500124 0.249936)
			(stroke
				(width 0.1)
				(type default)
			)
			(layer "F.Fab")
		)
		(fp_line
			(start -0.8001 0.249936)
			(end -0.8001 0.700024)
			(stroke
				(width 0.1)
				(type default)
			)
			(layer "F.Fab")
		)
		(fp_line
			(start -1.500124 0.249936)
			(end -1.500124 -0.249936)
			(stroke
				(width 0.1)
				(type default)
			)
			(layer "F.Fab")
		)
		(fp_line
			(start 1.500124 0.700024)
			(end 1.500124 1.199896)
			(stroke
				(width 0.1)
				(type default)
			)
			(layer "F.Fab")
		)
		(fp_line
			(start 0.700024 0.700024)
			(end 1.500124 0.700024)
			(stroke
				(width 0.1)
				(type default)
			)
			(layer "F.Fab")
		)
		(fp_line
			(start -0.700024 0.700024)
			(end -0.700024 1.199896)
			(stroke
				(width 0.1)
				(type default)
			)
			(layer "F.Fab")
		)
		(fp_line
			(start -1.500124 0.700024)
			(end -0.700024 0.700024)
			(stroke
				(width 0.1)
				(type default)
			)
			(layer "F.Fab")
		)
		(fp_line
			(start 1.500124 1.199896)
			(end 0.700024 1.199896)
			(stroke
				(width 0.1)
				(type default)
			)
			(layer "F.Fab")
		)
		(fp_line
			(start 0.700024 1.199896)
			(end 0.700024 0.700024)
			(stroke
				(width 0.1)
				(type default)
			)
			(layer "F.Fab")
		)
		(fp_line
			(start -0.700024 1.199896)
			(end -1.500124 1.199896)
			(stroke
				(width 0.1)
				(type default)
			)
			(layer "F.Fab")
		)
		(fp_line
			(start -0.8001 1.199896)
			(end -0.8001 1.450086)
			(stroke
				(width 0.1)
				(type default)
			)
			(layer "F.Fab")
		)
		(fp_line
			(start -1.500124 1.199896)
			(end -1.500124 0.700024)
			(stroke
				(width 0.1)
				(type default)
			)
			(layer "F.Fab")
		)
		(fp_line
			(start 0.599948 1.249934)
			(end -0.599948 1.249934)
			(stroke
				(width 0.1)
				(type default)
			)
			(layer "F.Fab")
		)
		(fp_line
			(start -0.599948 1.249934)
			(end -0.599948 -1.249934)
			(stroke
				(width 0.1)
				(type default)
			)
			(layer "F.Fab")
		)
		(fp_line
			(start 0.8001 1.450086)
			(end 0.8001 1.199896)
			(stroke
				(width 0.1)
				(type default)
			)
			(layer "F.Fab")
		)
		(fp_line
			(start 0.8001 1.450086)
			(end 0.599948 1.249934)
			(stroke
				(width 0.1)
				(type default)
			)
			(layer "F.Fab")
		)
		(fp_line
			(start -0.8001 1.450086)
			(end -0.599948 1.249934)
			(stroke
				(width 0.1)
				(type default)
			)
			(layer "F.Fab")
		)
		(fp_line
			(start -0.8001 1.450086)
			(end 0.8001 1.450086)
			(stroke
				(width 0.1)
				(type default)
			)
			(layer "F.Fab")
		)
		(fp_poly
			(pts
				(arc
					(start -0.350012 -0.799846)
					(mid -0.350012 -1.100074)
					(end -0.350012 -0.799846)
				)
			)
			(stroke
				(width 0)
				(type default)
			)
			(fill yes)
			(layer "F.Fab")
		)
		(fp_text user "6"
			(at 1.570228 -1.765046 0)
			(unlocked yes)
			(layer "F.SilkS")
			(effects
				(font
					(size 0.635 0.4064)
					(thickness 0.1524)
				)
			)
		)
		(fp_text user "4"
			(at 2.76225 2.032 0)
			(unlocked yes)
			(layer "F.SilkS")
			(effects
				(font
					(size 0.635 0.4064)
					(thickness 0.1524)
				)
			)
		)
		(fp_text user "3"
			(at -2.06375 2.159 0)
			(unlocked yes)
			(layer "F.SilkS")
			(effects
				(font
					(size 0.635 0.4064)
					(thickness 0.1524)
				)
			)
		)
		(fp_text user "6"
			(at 2.572258 -1.0668 0)
			(unlocked yes)
			(layer "F.Fab")
			(effects
				(font
					(size 0.7874 0.5842)
					(thickness 0.1524)
				)
			)
		)
		(fp_text user "4"
			(at 2.623058 0.8636 0)
			(unlocked yes)
			(layer "F.Fab")
			(effects
				(font
					(size 0.7874 0.5842)
					(thickness 0.1524)
				)
			)
		)
		(fp_text user "3"
			(at -2.429256 1.155954 0)
			(unlocked yes)
			(layer "F.Fab")
			(effects
				(font
					(size 0.7874 0.5842)
					(thickness 0.1524)
				)
			)
		)
		(pad "1" smd rect
			(at -1.4351 -0.94996 180)
			(size 0.508 1.1938)
			(layers "F.Cu" "F.Mask" "F.Paste")
			(net "Net_756")
		)
		(pad "2" smd rect
			(at -1.4351 0 180)
			(size 0.508 1.1938)
			(layers "F.Cu" "F.Mask" "F.Paste")
			(net "SG")
		)
		(pad "3" smd rect
			(at -1.4351 0.94996 180)
			(size 0.508 1.1938)
			(layers "F.Cu" "F.Mask" "F.Paste")
			(net "Net_755")
		)
		(pad "4" smd rect
			(at 1.4351 0.94996 180)
			(size 0.508 1.1938)
			(layers "F.Cu" "F.Mask" "F.Paste")
			(net "FT_USB_DM")
		)
		(pad "5" smd rect
			(at 1.4351 0 180)
			(size 0.508 1.1938)
			(layers "F.Cu" "F.Mask" "F.Paste")
			(net "XP5R0V_FT4232")
		)
		(pad "6" smd rect
			(at 1.4351 -0.94996 180)
			(size 0.508 1.1938)
			(layers "F.Cu" "F.Mask" "F.Paste")
			(net "FT_USB_DP")
		)
	)
	(footprint ""
		(layer "F.Cu")
		(at 13.462 -37.211 -90)
		(property "Reference" "R156"
			(at 1.27 3.51663 90)
			(unlocked yes)
			(layer "F.SilkS")
			(effects
				(font
					(size 0.7874 0.5842)
					(thickness 0.1524)
				)
			)
		)
		(property "Value" "VAL*"
			(at 0.02032 2.13233 270)
			(unlocked yes)
			(layer "F.Fab")
			(hide yes)
			(effects
				(font
					(size 0.7874 0.5842)
					(thickness 0.1524)
				)
			)
		)
		(property "Tolerance" "TOL*"
			(at 0.044704 3.05435 270)
			(unlocked yes)
			(layer "Cmts.User")
			(hide yes)
			(effects
				(font
					(size 0.7874 0.5842)
					(thickness 0.1524)
				)
			)
		)
		(property "User Part Number" "PARTNUM*"
			(at 0.02032 4.024884 270)
			(unlocked yes)
			(layer "Cmts.User")
			(hide yes)
			(effects
				(font
					(size 0.7874 0.5842)
					(thickness 0.1524)
				)
			)
		)
		(property "Device Type" "RESISTOR-G155-11000-01,100OHM,A"
			(at 0.008382 1.210564 270)
			(unlocked yes)
			(layer "F.Fab")
			(hide yes)
			(effects
				(font
					(size 0.7874 0.5842)
					(thickness 0.1524)
				)
			)
		)
		(duplicate_pad_numbers_are_jumpers no)
		(fp_line
			(start -1.143 0.5588)
			(end 1.143 0.5588)
			(stroke
				(width 0.1)
				(type default)
			)
			(layer "F.SilkS")
		)
		(fp_line
			(start 1.143 0.5588)
			(end 1.143 -0.5588)
			(stroke
				(width 0.1)
				(type default)
			)
			(layer "F.SilkS")
		)
		(fp_line
			(start -1.143 -0.5588)
			(end -1.143 0.5588)
			(stroke
				(width 0.1)
				(type default)
			)
			(layer "F.SilkS")
		)
		(fp_line
			(start 1.143 -0.5588)
			(end -1.143 -0.5588)
			(stroke
				(width 0.1)
				(type default)
			)
			(layer "F.SilkS")
		)
		(fp_poly
			(pts
				(xy -1.143 0.5588) (xy 1.143 0.5588) (xy 1.143 -0.5588) (xy -1.143 -0.5588)
			)
			(stroke
				(width 0)
				(type default)
			)
			(fill no)
			(layer "F.CrtYd")
		)
		(fp_line
			(start -0.508 0.3048)
			(end 0.508 0.3048)
			(stroke
				(width 0.1)
				(type default)
			)
			(layer "F.Fab")
		)
		(fp_line
			(start 0.508 0.3048)
			(end 0.508 -0.3048)
			(stroke
				(width 0.1)
				(type default)
			)
			(layer "F.Fab")
		)
		(fp_line
			(start -0.508 -0.3048)
			(end -0.508 0.3048)
			(stroke
				(width 0.1)
				(type default)
			)
			(layer "F.Fab")
		)
		(fp_line
			(start 0.508 -0.3048)
			(end -0.508 -0.3048)
			(stroke
				(width 0.1)
				(type default)
			)
			(layer "F.Fab")
		)
		(pad "1" smd rect
			(at -0.5334 0 270)
			(size 0.7112 0.6096)
			(layers "F.Cu" "F.Mask" "F.Paste")
			(net "ANT3_OUT")
		)
		(pad "2" smd rect
			(at 0.5334 0 270)
			(size 0.7112 0.6096)
			(layers "F.Cu" "F.Mask" "F.Paste")
			(net "UNNAMED_12_74HCT2G125DPTSSOP8_I")
		)
		(zone
			(layer "F.Cu")
			(hatch none 0.5)
			(connect_pads
				(clearance 0)
			)
			(min_thickness 0.25)
			(keepout
				(tracks not_allowed)
				(vias allowed)
				(pads allowed)
				(copperpour not_allowed)
				(footprints allowed)
			)
			(placement
				(enabled no)
				(sheetname "")
			)
			(fill
				(thermal_gap 0.5)
				(thermal_bridge_width 0.5)
				(island_removal_mode 0)
			)
			(polygon
				(pts
					(xy 13.1572 -37.2872) (xy 13.1572 -37.1348) (xy 13.7668 -37.1348) (xy 13.7668 -37.2872)
				)
			)
		)
		(zone
			(layer "F.Cu")
			(hatch none 0.5)
			(connect_pads
				(clearance 0)
			)
			(min_thickness 0.25)
			(keepout
				(tracks allowed)
				(vias not_allowed)
				(pads allowed)
				(copperpour not_allowed)
				(footprints allowed)
			)
			(placement
				(enabled no)
				(sheetname "")
			)
			(fill
				(thermal_gap 0.5)
				(thermal_bridge_width 0.5)
				(island_removal_mode 0)
			)
			(polygon
				(pts
					(xy 13.1572 -37.2872) (xy 13.1572 -37.1348) (xy 13.7668 -37.1348) (xy 13.7668 -37.2872)
				)
			)
		)
	)
	(footprint ""
		(layer "F.Cu")
		(at 55.88 -131.064)
		(property "Reference" "SP70"
			(at 0 0 0)
			(layer "F.SilkS")
			(hide yes)
			(effects
				(font
					(size 1.27 1.27)
				)
			)
		)
		(property "Value" ""
			(at 0 0 0)
			(layer "F.Fab")
			(effects
				(font
					(size 1.27 1.27)
				)
			)
		)
		(duplicate_pad_numbers_are_jumpers no)
	)
)
